(kicad_pcb
	(version 20260206)
	(generator "pcbnew")
	(generator_version "10.0")
	(general
		(thickness 1.6)
		(legacy_teardrops no)
	)
	(paper "A4")
	(title_block
		(title "04192023_DAF0TMB3IC0_F0TG_MB_C_brd_V02_OCP.brd")
		(comment 1 "Grand Teton / footprints 2188-2194 of 8354")
	)
	(layers
		(0 "F.Cu" signal "TOP")
		(4 "In1.Cu" signal "GND")
		(6 "In2.Cu" signal "IN1")
		(8 "In3.Cu" signal "GND1")
		(10 "In4.Cu" signal "IN2")
		(12 "In5.Cu" signal "GND2")
		(14 "In6.Cu" signal "IN3")
		(16 "In7.Cu" signal "GND3")
		(18 "In8.Cu" signal "VCC")
		(20 "In9.Cu" signal "VCC1")
		(22 "In10.Cu" signal "GND4")
		(24 "In11.Cu" signal "IN4")
		(26 "In12.Cu" signal "GND5")
		(28 "In13.Cu" signal "IN5")
		(30 "In14.Cu" signal "GND6")
		(32 "In15.Cu" signal "IN6")
		(34 "In16.Cu" signal "GND7")
		(2 "B.Cu" signal "BOTTOM")
		(9 "F.Adhes" user "F.Adhesive")
		(11 "B.Adhes" user "B.Adhesive")
		(13 "F.Paste" user "Package Geometry/Pastemask Top")
		(15 "B.Paste" user "Package Geometry/Pastemask Bottom")
		(5 "F.SilkS" user "Ref Des/Silkscreen Top")
		(7 "B.SilkS" user "Ref Des/Silkscreen Bottom")
		(1 "F.Mask" user "Board Geometry/Soldermask Top")
		(3 "B.Mask" user "Board Geometry/Soldermask Bottom")
		(17 "Dwgs.User" user "User.Drawings")
		(19 "Cmts.User" user "User.Comments")
		(21 "Eco1.User" user "User.Eco1")
		(23 "Eco2.User" user "User.Eco2")
		(25 "Edge.Cuts" user "Board Geometry/Outline")
		(27 "Margin" user)
		(31 "F.CrtYd" user "Package Geometry/Place Bound Top")
		(29 "B.CrtYd" user "Package Geometry/Place Bound Bottom")
		(35 "F.Fab" user "Ref Des/Assembly Top")
		(33 "B.Fab" user "Ref Des/Assembly Bottom")
	)
	(footprint ""
		(layer "F.Cu")
		(at 393.225782 -416.899344 -90)
		(property "Reference" "C6579"
			(at 0 0 270)
			(layer "F.SilkS")
			(hide yes)
			(effects
				(font
					(size 1.27 1.27)
				)
			)
		)
		(property "Value" ""
			(at 0 0 270)
			(layer "F.Fab")
			(effects
				(font
					(size 1.27 1.27)
				)
			)
		)
		(duplicate_pad_numbers_are_jumpers no)
		(fp_line
			(start -0.299974 0.150114)
			(end -0.299974 -0.150114)
			(stroke
				(width 0.1)
				(type default)
			)
			(layer "F.Fab")
		)
		(fp_line
			(start 0.299974 0.150114)
			(end -0.299974 0.150114)
			(stroke
				(width 0.1)
				(type default)
			)
			(layer "F.Fab")
		)
		(fp_line
			(start -0.299974 -0.150114)
			(end 0.299974 -0.150114)
			(stroke
				(width 0.1)
				(type default)
			)
			(layer "F.Fab")
		)
		(fp_line
			(start 0.299974 -0.150114)
			(end 0.299974 0.150114)
			(stroke
				(width 0.1)
				(type default)
			)
			(layer "F.Fab")
		)
		(pad "1" smd rect
			(at -0.2667 0 270)
			(size 0.3048 0.381)
			(layers "F.Cu" "F.Mask" "F.Paste")
			(net "P5E_CPU0_P2_TX_BUF_C_DP<7>")
		)
		(pad "2" smd rect
			(at 0.2667 0 270)
			(size 0.3048 0.381)
			(layers "F.Cu" "F.Mask" "F.Paste")
			(net "P5E_CPU0_P2_TX_BUF_DP<7>")
		)
	)
	(footprint ""
		(layer "F.Cu")
		(at 372.937278 -138.424158)
		(property "Reference" "R8300"
			(at 0 0 0)
			(layer "F.SilkS")
			(hide yes)
			(effects
				(font
					(size 1.27 1.27)
				)
			)
		)
		(property "Value" ""
			(at 0 0 0)
			(layer "F.Fab")
			(effects
				(font
					(size 1.27 1.27)
				)
			)
		)
		(duplicate_pad_numbers_are_jumpers no)
		(fp_line
			(start -0.7874 -0.4064)
			(end 0.7874 -0.4064)
			(stroke
				(width 0.1524)
				(type default)
			)
			(layer "F.SilkS")
		)
		(fp_line
			(start -0.7874 0.4064)
			(end -0.7874 -0.4064)
			(stroke
				(width 0.1524)
				(type default)
			)
			(layer "F.SilkS")
		)
		(fp_line
			(start 0.7874 -0.4064)
			(end 0.7874 0.4064)
			(stroke
				(width 0.1524)
				(type default)
			)
			(layer "F.SilkS")
		)
		(fp_line
			(start 0.7874 0.4064)
			(end -0.7874 0.4064)
			(stroke
				(width 0.1524)
				(type default)
			)
			(layer "F.SilkS")
		)
		(fp_line
			(start -0.67945 -0.305054)
			(end -0.12065 -0.305054)
			(stroke
				(width 0.1)
				(type default)
			)
			(layer "F.Fab")
		)
		(fp_line
			(start -0.67945 0.3048)
			(end -0.67945 -0.305054)
			(stroke
				(width 0.1)
				(type default)
			)
			(layer "F.Fab")
		)
		(fp_line
			(start -0.12065 -0.305054)
			(end -0.12065 -0.2794)
			(stroke
				(width 0.1)
				(type default)
			)
			(layer "F.Fab")
		)
		(fp_line
			(start -0.12065 -0.2794)
			(end 0.12065 -0.2794)
			(stroke
				(width 0.1)
				(type default)
			)
			(layer "F.Fab")
		)
		(fp_line
			(start -0.12065 0.2794)
			(end -0.12065 0.3048)
			(stroke
				(width 0.1)
				(type default)
			)
			(layer "F.Fab")
		)
		(fp_line
			(start -0.12065 0.3048)
			(end -0.67945 0.3048)
			(stroke
				(width 0.1)
				(type default)
			)
			(layer "F.Fab")
		)
		(fp_line
			(start 0.120396 0.2794)
			(end -0.12065 0.2794)
			(stroke
				(width 0.1)
				(type default)
			)
			(layer "F.Fab")
		)
		(fp_line
			(start 0.120396 0.3048)
			(end 0.120396 0.2794)
			(stroke
				(width 0.1)
				(type default)
			)
			(layer "F.Fab")
		)
		(fp_line
			(start 0.12065 -0.3048)
			(end 0.67945 -0.3048)
			(stroke
				(width 0.1)
				(type default)
			)
			(layer "F.Fab")
		)
		(fp_line
			(start 0.12065 -0.2794)
			(end 0.12065 -0.3048)
			(stroke
				(width 0.1)
				(type default)
			)
			(layer "F.Fab")
		)
		(fp_line
			(start 0.67945 -0.3048)
			(end 0.67945 0.3048)
			(stroke
				(width 0.1)
				(type default)
			)
			(layer "F.Fab")
		)
		(fp_line
			(start 0.67945 0.3048)
			(end 0.120396 0.3048)
			(stroke
				(width 0.1)
				(type default)
			)
			(layer "F.Fab")
		)
		(pad "1" smd circle
			(at -0.40005 0)
			(size 0 0)
			(layers "F.Cu" "F.Mask" "F.Paste")
			(net "P3V3_AUX")
		)
		(pad "2" smd circle
			(at 0.40005 0)
			(size 0 0)
			(layers "F.Cu" "F.Mask" "F.Paste")
			(net "PWRGD_PVDDCR_CPU0_P0_R")
		)
	)
	(footprint ""
		(layer "F.Cu")
		(at 288.87928 -394.985748 -90)
		(property "Reference" "C1072"
			(at 0 0 270)
			(layer "F.SilkS")
			(hide yes)
			(effects
				(font
					(size 1.27 1.27)
				)
			)
		)
		(property "Value" ""
			(at 0 0 270)
			(layer "F.Fab")
			(effects
				(font
					(size 1.27 1.27)
				)
			)
		)
		(duplicate_pad_numbers_are_jumpers no)
		(fp_line
			(start -0.299974 0.150114)
			(end -0.299974 -0.150114)
			(stroke
				(width 0.1)
				(type default)
			)
			(layer "F.Fab")
		)
		(fp_line
			(start 0.299974 0.150114)
			(end -0.299974 0.150114)
			(stroke
				(width 0.1)
				(type default)
			)
			(layer "F.Fab")
		)
		(fp_line
			(start -0.299974 -0.150114)
			(end 0.299974 -0.150114)
			(stroke
				(width 0.1)
				(type default)
			)
			(layer "F.Fab")
		)
		(fp_line
			(start 0.299974 -0.150114)
			(end 0.299974 0.150114)
			(stroke
				(width 0.1)
				(type default)
			)
			(layer "F.Fab")
		)
		(pad "1" smd rect
			(at -0.2667 0 270)
			(size 0.3048 0.381)
			(layers "F.Cu" "F.Mask" "F.Paste")
			(net "P3V3_AUX")
		)
		(pad "2" smd rect
			(at 0.2667 0 270)
			(size 0.3048 0.381)
			(layers "F.Cu" "F.Mask" "F.Paste")
			(net "GND")
		)
	)
	(footprint ""
		(layer "F.Cu")
		(at 352.05543 -433.841652 180)
		(property "Reference" "R4555"
			(at 0 0 180)
			(layer "F.SilkS")
			(hide yes)
			(effects
				(font
					(size 1.27 1.27)
				)
			)
		)
		(property "Value" ""
			(at 0 0 180)
			(layer "F.Fab")
			(effects
				(font
					(size 1.27 1.27)
				)
			)
		)
		(duplicate_pad_numbers_are_jumpers no)
		(fp_line
			(start 0.7874 0.4064)
			(end -0.7874 0.4064)
			(stroke
				(width 0.1524)
				(type default)
			)
			(layer "F.SilkS")
		)
		(fp_line
			(start 0.7874 -0.4064)
			(end 0.7874 0.4064)
			(stroke
				(width 0.1524)
				(type default)
			)
			(layer "F.SilkS")
		)
		(fp_line
			(start -0.7874 0.4064)
			(end -0.7874 -0.4064)
			(stroke
				(width 0.1524)
				(type default)
			)
			(layer "F.SilkS")
		)
		(fp_line
			(start -0.7874 -0.4064)
			(end 0.7874 -0.4064)
			(stroke
				(width 0.1524)
				(type default)
			)
			(layer "F.SilkS")
		)
		(fp_line
			(start 0.67945 0.3048)
			(end 0.120396 0.3048)
			(stroke
				(width 0.1)
				(type default)
			)
			(layer "F.Fab")
		)
		(fp_line
			(start 0.67945 -0.3048)
			(end 0.67945 0.3048)
			(stroke
				(width 0.1)
				(type default)
			)
			(layer "F.Fab")
		)
		(fp_line
			(start 0.12065 -0.2794)
			(end 0.12065 -0.3048)
			(stroke
				(width 0.1)
				(type default)
			)
			(layer "F.Fab")
		)
		(fp_line
			(start 0.12065 -0.3048)
			(end 0.67945 -0.3048)
			(stroke
				(width 0.1)
				(type default)
			)
			(layer "F.Fab")
		)
		(fp_line
			(start 0.120396 0.3048)
			(end 0.120396 0.2794)
			(stroke
				(width 0.1)
				(type default)
			)
			(layer "F.Fab")
		)
		(fp_line
			(start 0.120396 0.2794)
			(end -0.12065 0.2794)
			(stroke
				(width 0.1)
				(type default)
			)
			(layer "F.Fab")
		)
		(fp_line
			(start -0.12065 0.3048)
			(end -0.67945 0.3048)
			(stroke
				(width 0.1)
				(type default)
			)
			(layer "F.Fab")
		)
		(fp_line
			(start -0.12065 0.2794)
			(end -0.12065 0.3048)
			(stroke
				(width 0.1)
				(type default)
			)
			(layer "F.Fab")
		)
		(fp_line
			(start -0.12065 -0.2794)
			(end 0.12065 -0.2794)
			(stroke
				(width 0.1)
				(type default)
			)
			(layer "F.Fab")
		)
		(fp_line
			(start -0.12065 -0.305054)
			(end -0.12065 -0.2794)
			(stroke
				(width 0.1)
				(type default)
			)
			(layer "F.Fab")
		)
		(fp_line
			(start -0.67945 0.3048)
			(end -0.67945 -0.305054)
			(stroke
				(width 0.1)
				(type default)
			)
			(layer "F.Fab")
		)
		(fp_line
			(start -0.67945 -0.305054)
			(end -0.12065 -0.305054)
			(stroke
				(width 0.1)
				(type default)
			)
			(layer "F.Fab")
		)
		(pad "1" smd circle
			(at -0.40005 0 180)
			(size 0 0)
			(layers "F.Cu" "F.Mask" "F.Paste")
			(net "SWB_HSC_EN_BUF_R")
		)
		(pad "2" smd circle
			(at 0.40005 0 180)
			(size 0 0)
			(layers "F.Cu" "F.Mask" "F.Paste")
			(net "GND")
		)
	)
	(footprint ""
		(layer "F.Cu")
		(at 211.572348 -14.892528)
		(property "Reference" "C1275"
			(at 0 0 0)
			(layer "F.SilkS")
			(hide yes)
			(effects
				(font
					(size 1.27 1.27)
				)
			)
		)
		(property "Value" ""
			(at 0 0 0)
			(layer "F.Fab")
			(effects
				(font
					(size 1.27 1.27)
				)
			)
		)
		(duplicate_pad_numbers_are_jumpers no)
		(fp_line
			(start -0.7874 -0.4064)
			(end 0.7874 -0.4064)
			(stroke
				(width 0.1524)
				(type default)
			)
			(layer "F.SilkS")
		)
		(fp_line
			(start -0.7874 0.4064)
			(end -0.7874 -0.4064)
			(stroke
				(width 0.1524)
				(type default)
			)
			(layer "F.SilkS")
		)
		(fp_line
			(start 0.7874 -0.4064)
			(end 0.7874 0.4064)
			(stroke
				(width 0.1524)
				(type default)
			)
			(layer "F.SilkS")
		)
		(fp_line
			(start 0.7874 0.4064)
			(end -0.7874 0.4064)
			(stroke
				(width 0.1524)
				(type default)
			)
			(layer "F.SilkS")
		)
		(fp_line
			(start -0.67945 -0.305054)
			(end -0.12065 -0.305054)
			(stroke
				(width 0.1)
				(type default)
			)
			(layer "F.Fab")
		)
		(fp_line
			(start -0.67945 0.3048)
			(end -0.67945 -0.305054)
			(stroke
				(width 0.1)
				(type default)
			)
			(layer "F.Fab")
		)
		(fp_line
			(start -0.12065 -0.305054)
			(end -0.12065 -0.2794)
			(stroke
				(width 0.1)
				(type default)
			)
			(layer "F.Fab")
		)
		(fp_line
			(start -0.12065 -0.2794)
			(end 0.12065 -0.2794)
			(stroke
				(width 0.1)
				(type default)
			)
			(layer "F.Fab")
		)
		(fp_line
			(start -0.12065 0.2794)
			(end -0.12065 0.3048)
			(stroke
				(width 0.1)
				(type default)
			)
			(layer "F.Fab")
		)
		(fp_line
			(start -0.12065 0.3048)
			(end -0.67945 0.3048)
			(stroke
				(width 0.1)
				(type default)
			)
			(layer "F.Fab")
		)
		(fp_line
			(start 0.120396 0.2794)
			(end -0.12065 0.2794)
			(stroke
				(width 0.1)
				(type default)
			)
			(layer "F.Fab")
		)
		(fp_line
			(start 0.120396 0.3048)
			(end 0.120396 0.2794)
			(stroke
				(width 0.1)
				(type default)
			)
			(layer "F.Fab")
		)
		(fp_line
			(start 0.12065 -0.3048)
			(end 0.67945 -0.3048)
			(stroke
				(width 0.1)
				(type default)
			)
			(layer "F.Fab")
		)
		(fp_line
			(start 0.12065 -0.2794)
			(end 0.12065 -0.3048)
			(stroke
				(width 0.1)
				(type default)
			)
			(layer "F.Fab")
		)
		(fp_line
			(start 0.67945 -0.3048)
			(end 0.67945 0.3048)
			(stroke
				(width 0.1)
				(type default)
			)
			(layer "F.Fab")
		)
		(fp_line
			(start 0.67945 0.3048)
			(end 0.120396 0.3048)
			(stroke
				(width 0.1)
				(type default)
			)
			(layer "F.Fab")
		)
		(pad "1" smd circle
			(at -0.40005 0)
			(size 0 0)
			(layers "F.Cu" "F.Mask" "F.Paste")
			(net "P3V3_AUX")
		)
		(pad "2" smd circle
			(at 0.40005 0)
			(size 0 0)
			(layers "F.Cu" "F.Mask" "F.Paste")
			(net "GND")
		)
	)
	(footprint ""
		(layer "F.Cu")
		(at 286.0675 -409.277058 -90)
		(property "Reference" "Q6001"
			(at 1.861566 -2.29997 90)
			(unlocked yes)
			(layer "F.SilkS")
			(effects
				(font
					(size 0.7874 0.5842)
					(thickness 0.1524)
				)
				(justify left)
			)
		)
		(property "Value" ""
			(at 0 0 270)
			(layer "F.Fab")
			(effects
				(font
					(size 1.27 1.27)
				)
			)
		)
		(duplicate_pad_numbers_are_jumpers no)
		(fp_line
			(start -1.905 1.651)
			(end -1.905 -1.651)
			(stroke
				(width 0.1524)
				(type default)
			)
			(layer "F.SilkS")
		)
		(fp_line
			(start 1.905 1.651)
			(end -1.905 1.651)
			(stroke
				(width 0.1524)
				(type default)
			)
			(layer "F.SilkS")
		)
		(fp_line
			(start -1.905 -1.651)
			(end 1.905 -1.651)
			(stroke
				(width 0.1524)
				(type default)
			)
			(layer "F.SilkS")
		)
		(fp_line
			(start 1.905 -1.651)
			(end 1.905 1.651)
			(stroke
				(width 0.1524)
				(type default)
			)
			(layer "F.SilkS")
		)
		(fp_line
			(start -0.649986 1.524)
			(end -0.649986 1.169924)
			(stroke
				(width 0.1)
				(type default)
			)
			(layer "F.Fab")
		)
		(fp_line
			(start 0.6985 1.524)
			(end -0.649986 1.524)
			(stroke
				(width 0.1)
				(type default)
			)
			(layer "F.Fab")
		)
		(fp_line
			(start -1.249934 1.169924)
			(end -1.249934 0.729996)
			(stroke
				(width 0.1)
				(type default)
			)
			(layer "F.Fab")
		)
		(fp_line
			(start -0.649986 1.169924)
			(end -1.249934 1.169924)
			(stroke
				(width 0.1)
				(type default)
			)
			(layer "F.Fab")
		)
		(fp_line
			(start -1.249934 0.729996)
			(end -0.6985 0.729996)
			(stroke
				(width 0.1)
				(type default)
			)
			(layer "F.Fab")
		)
		(fp_line
			(start -0.6985 0.729996)
			(end -0.6985 -0.729996)
			(stroke
				(width 0.1)
				(type default)
			)
			(layer "F.Fab")
		)
		(fp_line
			(start 0.6985 0.219964)
			(end 0.6985 1.524)
			(stroke
				(width 0.1)
				(type default)
			)
			(layer "F.Fab")
		)
		(fp_line
			(start 1.249934 0.219964)
			(end 0.6985 0.219964)
			(stroke
				(width 0.1)
				(type default)
			)
			(layer "F.Fab")
		)
		(fp_line
			(start 0.6985 -0.219964)
			(end 1.249934 -0.219964)
			(stroke
				(width 0.1)
				(type default)
			)
			(layer "F.Fab")
		)
		(fp_line
			(start 1.249934 -0.219964)
			(end 1.249934 0.219964)
			(stroke
				(width 0.1)
				(type default)
			)
			(layer "F.Fab")
		)
		(fp_line
			(start -1.249934 -0.729996)
			(end -1.249934 -1.169924)
			(stroke
				(width 0.1)
				(type default)
			)
			(layer "F.Fab")
		)
		(fp_line
			(start -0.6985 -0.729996)
			(end -1.249934 -0.729996)
			(stroke
				(width 0.1)
				(type default)
			)
			(layer "F.Fab")
		)
		(fp_line
			(start -1.249934 -1.169924)
			(end -0.649986 -1.169924)
			(stroke
				(width 0.1)
				(type default)
			)
			(layer "F.Fab")
		)
		(fp_line
			(start -0.649986 -1.169924)
			(end -0.649986 -1.524)
			(stroke
				(width 0.1)
				(type default)
			)
			(layer "F.Fab")
		)
		(fp_line
			(start -0.649986 -1.524)
			(end 0.6985 -1.524)
			(stroke
				(width 0.1)
				(type default)
			)
			(layer "F.Fab")
		)
		(fp_line
			(start 0.6985 -1.524)
			(end 0.6985 -0.219964)
			(stroke
				(width 0.1)
				(type default)
			)
			(layer "F.Fab")
		)
		(pad "B" smd rect
			(at -1.1176 -1.016 180)
			(size 1.016 1.27)
			(layers "F.Cu" "F.Mask" "F.Paste")
			(net "P12V_HSC_TEMP_R")
		)
		(pad "C" smd rect
			(at 1.1176 0 180)
			(size 1.016 1.27)
			(layers "F.Cu" "F.Mask" "F.Paste")
			(net "P12V_HSC_TEMP_R")
		)
		(pad "E" smd rect
			(at -1.1176 1.016 180)
			(size 1.016 1.27)
			(layers "F.Cu" "F.Mask" "F.Paste")
			(net "P12V_HSC_TEMP_E")
		)
	)
	(footprint ""
		(layer "F.Cu")
		(at 220.190822 -57.851802 180)
		(property "Reference" "R3758"
			(at 0 0 180)
			(layer "F.SilkS")
			(hide yes)
			(effects
				(font
					(size 1.27 1.27)
				)
			)
		)
		(property "Value" ""
			(at 0 0 180)
			(layer "F.Fab")
			(effects
				(font
					(size 1.27 1.27)
				)
			)
		)
		(duplicate_pad_numbers_are_jumpers no)
		(fp_line
			(start 0.7874 0.4064)
			(end -0.7874 0.4064)
			(stroke
				(width 0.1524)
				(type default)
			)
			(layer "F.SilkS")
		)
		(fp_line
			(start 0.7874 -0.4064)
			(end 0.7874 0.4064)
			(stroke
				(width 0.1524)
				(type default)
			)
			(layer "F.SilkS")
		)
		(fp_line
			(start -0.7874 0.4064)
			(end -0.7874 -0.4064)
			(stroke
				(width 0.1524)
				(type default)
			)
			(layer "F.SilkS")
		)
		(fp_line
			(start -0.7874 -0.4064)
			(end 0.7874 -0.4064)
			(stroke
				(width 0.1524)
				(type default)
			)
			(layer "F.SilkS")
		)
		(fp_line
			(start 0.67945 0.3048)
			(end 0.120396 0.3048)
			(stroke
				(width 0.1)
				(type default)
			)
			(layer "F.Fab")
		)
		(fp_line
			(start 0.67945 -0.3048)
			(end 0.67945 0.3048)
			(stroke
				(width 0.1)
				(type default)
			)
			(layer "F.Fab")
		)
		(fp_line
			(start 0.12065 -0.2794)
			(end 0.12065 -0.3048)
			(stroke
				(width 0.1)
				(type default)
			)
			(layer "F.Fab")
		)
		(fp_line
			(start 0.12065 -0.3048)
			(end 0.67945 -0.3048)
			(stroke
				(width 0.1)
				(type default)
			)
			(layer "F.Fab")
		)
		(fp_line
			(start 0.120396 0.3048)
			(end 0.120396 0.2794)
			(stroke
				(width 0.1)
				(type default)
			)
			(layer "F.Fab")
		)
		(fp_line
			(start 0.120396 0.2794)
			(end -0.12065 0.2794)
			(stroke
				(width 0.1)
				(type default)
			)
			(layer "F.Fab")
		)
		(fp_line
			(start -0.12065 0.3048)
			(end -0.67945 0.3048)
			(stroke
				(width 0.1)
				(type default)
			)
			(layer "F.Fab")
		)
		(fp_line
			(start -0.12065 0.2794)
			(end -0.12065 0.3048)
			(stroke
				(width 0.1)
				(type default)
			)
			(layer "F.Fab")
		)
		(fp_line
			(start -0.12065 -0.2794)
			(end 0.12065 -0.2794)
			(stroke
				(width 0.1)
				(type default)
			)
			(layer "F.Fab")
		)
		(fp_line
			(start -0.12065 -0.305054)
			(end -0.12065 -0.2794)
			(stroke
				(width 0.1)
				(type default)
			)
			(layer "F.Fab")
		)
		(fp_line
			(start -0.67945 0.3048)
			(end -0.67945 -0.305054)
			(stroke
				(width 0.1)
				(type default)
			)
			(layer "F.Fab")
		)
		(fp_line
			(start -0.67945 -0.305054)
			(end -0.12065 -0.305054)
			(stroke
				(width 0.1)
				(type default)
			)
			(layer "F.Fab")
		)
		(pad "1" smd circle
			(at -0.40005 0 180)
			(size 0 0)
			(layers "F.Cu" "F.Mask" "F.Paste")
			(net "P3V3_E1S_0_R")
		)
		(pad "2" smd circle
			(at 0.40005 0 180)
			(size 0 0)
			(layers "F.Cu" "F.Mask" "F.Paste")
			(net "VSENSE_P3V3_INA230_2_INP")
		)
	)
)
